(kicad_pcb
	(version 20260206)
	(generator "pcbnew")
	(generator_version "10.0")
	(general
		(thickness 1.6)
		(legacy_teardrops no)
	)
	(paper "A4")
	(title_block
		(title "fcb — 12433-1M.1206WZS1330.brd")
		(comment 1 "Open Vault / Knox (Wiwynn) / footprints 116-119 of 495")
	)
	(layers
		(0 "F.Cu" signal "TOP")
		(4 "In1.Cu" signal "L2GND")
		(6 "In2.Cu" signal "L3VCC")
		(2 "B.Cu" signal "BOTTOM")
		(9 "F.Adhes" user "F.Adhesive")
		(11 "B.Adhes" user "B.Adhesive")
		(13 "F.Paste" user "Package Geometry/Pastemask Top")
		(15 "B.Paste" user "Package Geometry/Pastemask Bottom")
		(5 "F.SilkS" user "Ref Des/Silkscreen Top")
		(7 "B.SilkS" user "Ref Des/Silkscreen Bottom")
		(1 "F.Mask" user "Board Geometry/Soldermask Top")
		(3 "B.Mask" user "Board Geometry/Soldermask Bottom")
		(17 "Dwgs.User" user "User.Drawings")
		(19 "Cmts.User" user "User.Comments")
		(21 "Eco1.User" user "User.Eco1")
		(23 "Eco2.User" user "User.Eco2")
		(25 "Edge.Cuts" user "Board Geometry/Outline")
		(27 "Margin" user)
		(31 "F.CrtYd" user "Package Geometry/Place Bound Top")
		(29 "B.CrtYd" user "Package Geometry/Place Bound Bottom")
		(35 "F.Fab" user "Ref Des/Assembly Top")
		(33 "B.Fab" user "Ref Des/Assembly Bottom")
	)
	(footprint ""
		(layer "F.Cu")
		(at 6.999986 -159.999934)
		(property "Reference" "H7"
			(at 0 0 0)
			(layer "F.SilkS")
			(hide yes)
			(effects
				(font
					(size 1.27 1.27)
				)
			)
		)
		(property "Value" "HOLE315R138"
			(at 0 -7.0612 0)
			(unlocked yes)
			(layer "F.Fab")
			(hide yes)
			(effects
				(font
					(size 1.016 1.016)
					(thickness 0.1524)
				)
			)
		)
		(property "Device Type" "HOLE315R138"
			(at 0 -8.5852 0)
			(unlocked yes)
			(layer "F.Fab")
			(hide yes)
			(effects
				(font
					(size 1.016 1.016)
					(thickness 0.1524)
				)
			)
		)
		(duplicate_pad_numbers_are_jumpers no)
		(fp_poly
			(pts
				(xy 0 4.3053) (xy -0.13462 4.30276) (xy -0.27051 4.29641) (xy -0.40513 4.28625) (xy -0.53975 4.27101)
				(xy -0.6731 4.25196) (xy -0.80645 4.2291) (xy -0.9398 4.20116) (xy -1.07061 4.17068) (xy -1.20142 4.13385)
				(xy -1.33096 4.09448) (xy -1.45796 4.0513) (xy -1.58496 4.00304) (xy -1.70942 3.95097) (xy -1.83261 3.89509)
				(xy -1.95453 3.83667) (xy -2.07391 3.77317) (xy -2.19202 3.70586) (xy -2.30632 3.63474) (xy -2.41935 3.56108)
				(xy -2.53111 3.48361) (xy -2.63906 3.40233) (xy -2.74447 3.31724) (xy -2.84734 3.22961) (xy -2.94767 3.13817)
				(xy -3.04419 3.04419) (xy -3.13817 2.94767) (xy -3.22961 2.84734) (xy -3.31724 2.74447) (xy -3.40233 2.63906)
				(xy -3.48361 2.53111) (xy -3.56108 2.41935) (xy -3.63474 2.30632) (xy -3.70586 2.19202) (xy -3.77317 2.07391)
				(xy -3.83667 1.95453) (xy -3.89509 1.83261) (xy -3.95097 1.70942) (xy -4.00304 1.58496) (xy -4.0513 1.45796)
				(xy -4.09448 1.33096) (xy -4.13385 1.20142) (xy -4.17068 1.07061) (xy -4.20116 0.9398) (xy -4.2291 0.80645)
				(xy -4.25196 0.6731) (xy -4.27101 0.53975) (xy -4.28625 0.40513) (xy -4.29641 0.27051) (xy -4.30276 0.13462)
				(xy -4.3053 0) (xy -4.30276 -0.13462) (xy -4.29641 -0.27051) (xy -4.28625 -0.40513) (xy -4.27101 -0.53975)
				(xy -4.25196 -0.6731) (xy -4.2291 -0.80645) (xy -4.20116 -0.9398) (xy -4.17068 -1.07061) (xy -4.13385 -1.20142)
				(xy -4.09448 -1.33096) (xy -4.0513 -1.45796) (xy -4.00304 -1.58496) (xy -3.95097 -1.70942) (xy -3.89509 -1.83261)
				(xy -3.83667 -1.95453) (xy -3.77317 -2.07391) (xy -3.70586 -2.19202) (xy -3.63474 -2.30632) (xy -3.56108 -2.41935)
				(xy -3.48361 -2.53111) (xy -3.40233 -2.63906) (xy -3.31724 -2.74447) (xy -3.22961 -2.84734) (xy -3.13817 -2.94767)
				(xy -3.04419 -3.04419) (xy -2.94767 -3.13817) (xy -2.84734 -3.22961) (xy -2.74447 -3.31724) (xy -2.63906 -3.40233)
				(xy -2.53111 -3.48361) (xy -2.41935 -3.56108) (xy -2.30632 -3.63474) (xy -2.19202 -3.70586) (xy -2.07391 -3.77317)
				(xy -1.95453 -3.83667) (xy -1.83261 -3.89509) (xy -1.70942 -3.95097) (xy -1.58496 -4.00304) (xy -1.45796 -4.0513)
				(xy -1.33096 -4.09448) (xy -1.20142 -4.13385) (xy -1.07061 -4.17068) (xy -0.9398 -4.20116) (xy -0.80645 -4.2291)
				(xy -0.6731 -4.25196) (xy -0.53975 -4.27101) (xy -0.40513 -4.28625) (xy -0.27051 -4.29641) (xy -0.13462 -4.30276)
				(xy 0 -4.3053) (xy 0.13462 -4.30276) (xy 0.27051 -4.29641) (xy 0.40513 -4.28625) (xy 0.53975 -4.27101)
				(xy 0.6731 -4.25196) (xy 0.80645 -4.2291) (xy 0.9398 -4.20116) (xy 1.07061 -4.17068) (xy 1.20142 -4.13385)
				(xy 1.33096 -4.09448) (xy 1.45796 -4.0513) (xy 1.58496 -4.00304) (xy 1.70942 -3.95097) (xy 1.83261 -3.89509)
				(xy 1.95453 -3.83667) (xy 2.07391 -3.77317) (xy 2.19202 -3.70586) (xy 2.30632 -3.63474) (xy 2.41935 -3.56108)
				(xy 2.53111 -3.48361) (xy 2.63906 -3.40233) (xy 2.74447 -3.31724) (xy 2.84734 -3.22961) (xy 2.94767 -3.13817)
				(xy 3.04419 -3.04419) (xy 3.13817 -2.94767) (xy 3.22961 -2.84734) (xy 3.31724 -2.74447) (xy 3.40233 -2.63906)
				(xy 3.48361 -2.53111) (xy 3.56108 -2.41935) (xy 3.63474 -2.30632) (xy 3.70586 -2.19202) (xy 3.77317 -2.07391)
				(xy 3.83667 -1.95453) (xy 3.89509 -1.83261) (xy 3.95097 -1.70942) (xy 4.00304 -1.58496) (xy 4.0513 -1.45796)
				(xy 4.09448 -1.33096) (xy 4.13385 -1.20142) (xy 4.17068 -1.07061) (xy 4.20116 -0.9398) (xy 4.2291 -0.80645)
				(xy 4.25196 -0.6731) (xy 4.27101 -0.53975) (xy 4.28625 -0.40513) (xy 4.29641 -0.27051) (xy 4.30276 -0.13462)
				(xy 4.3053 0) (xy 4.30276 0.13462) (xy 4.29641 0.27051) (xy 4.28625 0.40513) (xy 4.27101 0.53975)
				(xy 4.25196 0.6731) (xy 4.2291 0.80645) (xy 4.20116 0.9398) (xy 4.17068 1.07061) (xy 4.13385 1.20142)
				(xy 4.09448 1.33096) (xy 4.0513 1.45796) (xy 4.00304 1.58496) (xy 3.95097 1.70942) (xy 3.89509 1.83261)
				(xy 3.83667 1.95453) (xy 3.77317 2.07391) (xy 3.70586 2.19202) (xy 3.63474 2.30632) (xy 3.56108 2.41935)
				(xy 3.48361 2.53111) (xy 3.40233 2.63906) (xy 3.31724 2.74447) (xy 3.22961 2.84734) (xy 3.13817 2.94767)
				(xy 3.04419 3.04419) (xy 2.94767 3.13817) (xy 2.84734 3.22961) (xy 2.74447 3.31724) (xy 2.63906 3.40233)
				(xy 2.53111 3.48361) (xy 2.41935 3.56108) (xy 2.30632 3.63474) (xy 2.19202 3.70586) (xy 2.07391 3.77317)
				(xy 1.95453 3.83667) (xy 1.83261 3.89509) (xy 1.70942 3.95097) (xy 1.58496 4.00304) (xy 1.45796 4.0513)
				(xy 1.33096 4.09448) (xy 1.20142 4.13385) (xy 1.07061 4.17068) (xy 0.9398 4.20116) (xy 0.80645 4.2291)
				(xy 0.6731 4.25196) (xy 0.53975 4.27101) (xy 0.40513 4.28625) (xy 0.27051 4.29641) (xy 0.13462 4.30276)
			)
			(stroke
				(width 0)
				(type default)
			)
			(fill no)
			(layer "F.CrtYd")
		)
		(fp_poly
			(pts
				(xy 0 4.3053) (xy -0.13462 4.30276) (xy -0.27051 4.29641) (xy -0.40513 4.28625) (xy -0.53975 4.27101)
				(xy -0.6731 4.25196) (xy -0.80645 4.2291) (xy -0.9398 4.20116) (xy -1.07061 4.17068) (xy -1.20142 4.13385)
				(xy -1.33096 4.09448) (xy -1.45796 4.0513) (xy -1.58496 4.00304) (xy -1.70942 3.95097) (xy -1.83261 3.89509)
				(xy -1.95453 3.83667) (xy -2.07391 3.77317) (xy -2.19202 3.70586) (xy -2.30632 3.63474) (xy -2.41935 3.56108)
				(xy -2.53111 3.48361) (xy -2.63906 3.40233) (xy -2.74447 3.31724) (xy -2.84734 3.22961) (xy -2.94767 3.13817)
				(xy -3.04419 3.04419) (xy -3.13817 2.94767) (xy -3.22961 2.84734) (xy -3.31724 2.74447) (xy -3.40233 2.63906)
				(xy -3.48361 2.53111) (xy -3.56108 2.41935) (xy -3.63474 2.30632) (xy -3.70586 2.19202) (xy -3.77317 2.07391)
				(xy -3.83667 1.95453) (xy -3.89509 1.83261) (xy -3.95097 1.70942) (xy -4.00304 1.58496) (xy -4.0513 1.45796)
				(xy -4.09448 1.33096) (xy -4.13385 1.20142) (xy -4.17068 1.07061) (xy -4.20116 0.9398) (xy -4.2291 0.80645)
				(xy -4.25196 0.6731) (xy -4.27101 0.53975) (xy -4.28625 0.40513) (xy -4.29641 0.27051) (xy -4.30276 0.13462)
				(xy -4.3053 0) (xy -4.30276 -0.13462) (xy -4.29641 -0.27051) (xy -4.28625 -0.40513) (xy -4.27101 -0.53975)
				(xy -4.25196 -0.6731) (xy -4.2291 -0.80645) (xy -4.20116 -0.9398) (xy -4.17068 -1.07061) (xy -4.13385 -1.20142)
				(xy -4.09448 -1.33096) (xy -4.0513 -1.45796) (xy -4.00304 -1.58496) (xy -3.95097 -1.70942) (xy -3.89509 -1.83261)
				(xy -3.83667 -1.95453) (xy -3.77317 -2.07391) (xy -3.70586 -2.19202) (xy -3.63474 -2.30632) (xy -3.56108 -2.41935)
				(xy -3.48361 -2.53111) (xy -3.40233 -2.63906) (xy -3.31724 -2.74447) (xy -3.22961 -2.84734) (xy -3.13817 -2.94767)
				(xy -3.04419 -3.04419) (xy -2.94767 -3.13817) (xy -2.84734 -3.22961) (xy -2.74447 -3.31724) (xy -2.63906 -3.40233)
				(xy -2.53111 -3.48361) (xy -2.41935 -3.56108) (xy -2.30632 -3.63474) (xy -2.19202 -3.70586) (xy -2.07391 -3.77317)
				(xy -1.95453 -3.83667) (xy -1.83261 -3.89509) (xy -1.70942 -3.95097) (xy -1.58496 -4.00304) (xy -1.45796 -4.0513)
				(xy -1.33096 -4.09448) (xy -1.20142 -4.13385) (xy -1.07061 -4.17068) (xy -0.9398 -4.20116) (xy -0.80645 -4.2291)
				(xy -0.6731 -4.25196) (xy -0.53975 -4.27101) (xy -0.40513 -4.28625) (xy -0.27051 -4.29641) (xy -0.13462 -4.30276)
				(xy 0 -4.3053) (xy 0.13462 -4.30276) (xy 0.27051 -4.29641) (xy 0.40513 -4.28625) (xy 0.53975 -4.27101)
				(xy 0.6731 -4.25196) (xy 0.80645 -4.2291) (xy 0.9398 -4.20116) (xy 1.07061 -4.17068) (xy 1.20142 -4.13385)
				(xy 1.33096 -4.09448) (xy 1.45796 -4.0513) (xy 1.58496 -4.00304) (xy 1.70942 -3.95097) (xy 1.83261 -3.89509)
				(xy 1.95453 -3.83667) (xy 2.07391 -3.77317) (xy 2.19202 -3.70586) (xy 2.30632 -3.63474) (xy 2.41935 -3.56108)
				(xy 2.53111 -3.48361) (xy 2.63906 -3.40233) (xy 2.74447 -3.31724) (xy 2.84734 -3.22961) (xy 2.94767 -3.13817)
				(xy 3.04419 -3.04419) (xy 3.13817 -2.94767) (xy 3.22961 -2.84734) (xy 3.31724 -2.74447) (xy 3.40233 -2.63906)
				(xy 3.48361 -2.53111) (xy 3.56108 -2.41935) (xy 3.63474 -2.30632) (xy 3.70586 -2.19202) (xy 3.77317 -2.07391)
				(xy 3.83667 -1.95453) (xy 3.89509 -1.83261) (xy 3.95097 -1.70942) (xy 4.00304 -1.58496) (xy 4.0513 -1.45796)
				(xy 4.09448 -1.33096) (xy 4.13385 -1.20142) (xy 4.17068 -1.07061) (xy 4.20116 -0.9398) (xy 4.2291 -0.80645)
				(xy 4.25196 -0.6731) (xy 4.27101 -0.53975) (xy 4.28625 -0.40513) (xy 4.29641 -0.27051) (xy 4.30276 -0.13462)
				(xy 4.3053 0) (xy 4.30276 0.13462) (xy 4.29641 0.27051) (xy 4.28625 0.40513) (xy 4.27101 0.53975)
				(xy 4.25196 0.6731) (xy 4.2291 0.80645) (xy 4.20116 0.9398) (xy 4.17068 1.07061) (xy 4.13385 1.20142)
				(xy 4.09448 1.33096) (xy 4.0513 1.45796) (xy 4.00304 1.58496) (xy 3.95097 1.70942) (xy 3.89509 1.83261)
				(xy 3.83667 1.95453) (xy 3.77317 2.07391) (xy 3.70586 2.19202) (xy 3.63474 2.30632) (xy 3.56108 2.41935)
				(xy 3.48361 2.53111) (xy 3.40233 2.63906) (xy 3.31724 2.74447) (xy 3.22961 2.84734) (xy 3.13817 2.94767)
				(xy 3.04419 3.04419) (xy 2.94767 3.13817) (xy 2.84734 3.22961) (xy 2.74447 3.31724) (xy 2.63906 3.40233)
				(xy 2.53111 3.48361) (xy 2.41935 3.56108) (xy 2.30632 3.63474) (xy 2.19202 3.70586) (xy 2.07391 3.77317)
				(xy 1.95453 3.83667) (xy 1.83261 3.89509) (xy 1.70942 3.95097) (xy 1.58496 4.00304) (xy 1.45796 4.0513)
				(xy 1.33096 4.09448) (xy 1.20142 4.13385) (xy 1.07061 4.17068) (xy 0.9398 4.20116) (xy 0.80645 4.2291)
				(xy 0.6731 4.25196) (xy 0.53975 4.27101) (xy 0.40513 4.28625) (xy 0.27051 4.29641) (xy 0.13462 4.30276)
			)
			(stroke
				(width 0)
				(type default)
			)
			(fill no)
			(layer "F.Fab")
		)
		(pad "1" thru_hole circle
			(at 0 0)
			(size 8.001 8.001)
			(drill 3.5052)
			(layers "*.Cu" "*.Mask")
			(remove_unused_layers no)
			(net "GND")
			(clearance -1.7399)
			(thermal_gap 0.3048)
			(padstack
				(mode front_inner_back)
				(layer "Inner"
					(shape circle)
					(size 3.9116 3.9116)
					(clearance 0.3048)
				)
				(layer "B.Cu"
					(shape circle)
					(size 8.001 8.001)
					(clearance -1.7399)
				)
			)
		)
	)
	(footprint ""
		(layer "F.Cu")
		(at 28.9814 -96.5454 -90)
		(property "Reference" "C24"
			(at 0 0 270)
			(layer "F.SilkS")
			(hide yes)
			(effects
				(font
					(size 1.27 1.27)
				)
			)
		)
		(property "Value" "SCD1U50V3KX-GP"
			(at 0 -2.8194 270)
			(unlocked yes)
			(layer "F.Fab")
			(hide yes)
			(effects
				(font
					(size 1.016 1.016)
					(thickness 0.1524)
				)
			)
		)
		(property "Device Type" "C603H36"
			(at 0 -4.3434 270)
			(unlocked yes)
			(layer "F.Fab")
			(hide yes)
			(effects
				(font
					(size 1.016 1.016)
					(thickness 0.1524)
				)
			)
		)
		(duplicate_pad_numbers_are_jumpers no)
		(fp_line
			(start 0.508 0)
			(end -0.508 0)
			(stroke
				(width 0.2032)
				(type default)
			)
			(layer "F.SilkS")
		)
		(fp_rect
			(start -0.5842 1.3335)
			(end 0.5842 -1.3335)
			(stroke
				(width 0)
				(type default)
			)
			(fill no)
			(layer "F.CrtYd")
		)
		(fp_rect
			(start -0.5842 1.3335)
			(end 0.5842 -1.3335)
			(stroke
				(width 0)
				(type default)
			)
			(fill no)
			(layer "F.Fab")
		)
		(pad "1" smd custom
			(at 0 -0.762 270)
			(size 0.2159 0.2159)
			(layers "F.Cu" "F.Mask" "F.Paste")
			(net "P12VL")
			(options
				(clearance outline)
				(anchor circle)
			)
			(primitives
				(gr_poly
					(pts
						(arc
							(start -0.3302 -0.4318)
							(mid -0.402042 -0.402042)
							(end -0.4318 -0.3302)
						)
						(arc
							(start -0.4318 0.3302)
							(mid -0.402042 0.402042)
							(end -0.3302 0.4318)
						)
						(arc
							(start 0.3302 0.4318)
							(mid 0.402042 0.402042)
							(end 0.4318 0.3302)
						)
						(arc
							(start 0.4318 -0.3302)
							(mid 0.402042 -0.402042)
							(end 0.3302 -0.4318)
						)
					)
					(width 0)
					(fill yes)
				)
			)
		)
		(pad "2" smd custom
			(at 0 0.762 270)
			(size 0.2159 0.2159)
			(layers "F.Cu" "F.Mask" "F.Paste")
			(net "GND")
			(options
				(clearance outline)
				(anchor circle)
			)
			(primitives
				(gr_poly
					(pts
						(arc
							(start -0.3302 -0.4318)
							(mid -0.402042 -0.402042)
							(end -0.4318 -0.3302)
						)
						(arc
							(start -0.4318 0.3302)
							(mid -0.402042 0.402042)
							(end -0.3302 0.4318)
						)
						(arc
							(start 0.3302 0.4318)
							(mid 0.402042 0.402042)
							(end 0.4318 0.3302)
						)
						(arc
							(start 0.4318 -0.3302)
							(mid 0.402042 -0.402042)
							(end 0.3302 -0.4318)
						)
					)
					(width 0)
					(fill yes)
				)
			)
		)
	)
	(footprint ""
		(layer "F.Cu")
		(at 15.9258 -146.6088 90)
		(property "Reference" "R68"
			(at 0 0 90)
			(layer "F.SilkS")
			(hide yes)
			(effects
				(font
					(size 1.27 1.27)
				)
			)
		)
		(property "Value" "4K7R2F-GP"
			(at 0.064008 -3.993896 90)
			(unlocked yes)
			(layer "F.Fab")
			(hide yes)
			(effects
				(font
					(size 1.016 1.016)
					(thickness 0.1524)
				)
			)
		)
		(property "Device Type" "R402H16"
			(at 0.064008 -5.517896 90)
			(unlocked yes)
			(layer "F.Fab")
			(hide yes)
			(effects
				(font
					(size 1.016 1.016)
					(thickness 0.1524)
				)
			)
		)
		(duplicate_pad_numbers_are_jumpers no)
		(fp_line
			(start -0.508 -0.9398)
			(end -1.524 -0.9398)
			(stroke
				(width 0.1524)
				(type default)
			)
			(layer "F.SilkS")
		)
		(fp_line
			(start -1.524 -0.9398)
			(end -1.524 0.9398)
			(stroke
				(width 0.1524)
				(type default)
			)
			(layer "F.SilkS")
		)
		(fp_rect
			(start -0.508 0.9398)
			(end 0.508 -0.9398)
			(stroke
				(width 0)
				(type default)
			)
			(fill no)
			(layer "F.CrtYd")
		)
		(fp_rect
			(start -0.508 0.9398)
			(end 0.508 -0.9398)
			(stroke
				(width 0)
				(type default)
			)
			(fill no)
			(layer "F.Fab")
		)
		(pad "1" smd custom
			(at 0 -0.4445 90)
			(size 0.1397 0.1397)
			(layers "F.Cu" "F.Mask" "F.Paste")
			(net "P12V")
			(options
				(clearance outline)
				(anchor circle)
			)
			(primitives
				(gr_poly
					(pts
						(arc
							(start -0.1778 -0.2794)
							(mid -0.249642 -0.249642)
							(end -0.2794 -0.1778)
						)
						(arc
							(start -0.2794 0.1778)
							(mid -0.249642 0.249642)
							(end -0.1778 0.2794)
						)
						(arc
							(start 0.1778 0.2794)
							(mid 0.249642 0.249642)
							(end 0.2794 0.1778)
						)
						(arc
							(start 0.2794 -0.1778)
							(mid 0.249642 -0.249642)
							(end 0.1778 -0.2794)
						)
					)
					(width 0)
					(fill yes)
				)
			)
		)
		(pad "2" smd custom
			(at 0 0.4445 90)
			(size 0.1397 0.1397)
			(layers "F.Cu" "F.Mask" "F.Paste")
			(net "FAN_TACH9")
			(options
				(clearance outline)
				(anchor circle)
			)
			(primitives
				(gr_poly
					(pts
						(arc
							(start -0.1778 -0.2794)
							(mid -0.249642 -0.249642)
							(end -0.2794 -0.1778)
						)
						(arc
							(start -0.2794 0.1778)
							(mid -0.249642 0.249642)
							(end -0.1778 0.2794)
						)
						(arc
							(start 0.1778 0.2794)
							(mid 0.249642 0.249642)
							(end 0.2794 0.1778)
						)
						(arc
							(start 0.2794 -0.1778)
							(mid 0.249642 -0.249642)
							(end 0.1778 -0.2794)
						)
					)
					(width 0)
					(fill yes)
				)
			)
		)
	)
	(footprint ""
		(layer "F.Cu")
		(at 35.6616 -144.6784 180)
		(property "Reference" "PC92"
			(at 0 0 180)
			(layer "F.SilkS")
			(hide yes)
			(effects
				(font
					(size 1.27 1.27)
				)
			)
		)
		(property "Value" "SCD01U50V3KX-4GP"
			(at 0 -2.8194 180)
			(unlocked yes)
			(layer "F.Fab")
			(hide yes)
			(effects
				(font
					(size 1.016 1.016)
					(thickness 0.1524)
				)
			)
		)
		(property "Device Type" "C603H36"
			(at 0 -4.3434 180)
			(unlocked yes)
			(layer "F.Fab")
			(hide yes)
			(effects
				(font
					(size 1.016 1.016)
					(thickness 0.1524)
				)
			)
		)
		(duplicate_pad_numbers_are_jumpers no)
		(fp_line
			(start 0.508 0)
			(end -0.508 0)
			(stroke
				(width 0.2032)
				(type default)
			)
			(layer "F.SilkS")
		)
		(fp_rect
			(start -0.5842 1.3335)
			(end 0.5842 -1.3335)
			(stroke
				(width 0)
				(type default)
			)
			(fill no)
			(layer "F.CrtYd")
		)
		(fp_rect
			(start -0.5842 1.3335)
			(end 0.5842 -1.3335)
			(stroke
				(width 0)
				(type default)
			)
			(fill no)
			(layer "F.Fab")
		)
		(pad "1" smd custom
			(at 0 -0.762 180)
			(size 0.2159 0.2159)
			(layers "F.Cu" "F.Mask" "F.Paste")
			(net "P12VL_2490_TIMER")
			(options
				(clearance outline)
				(anchor circle)
			)
			(primitives
				(gr_poly
					(pts
						(arc
							(start -0.3302 -0.4318)
							(mid -0.402042 -0.402042)
							(end -0.4318 -0.3302)
						)
						(arc
							(start -0.4318 0.3302)
							(mid -0.402042 0.402042)
							(end -0.3302 0.4318)
						)
						(arc
							(start 0.3302 0.4318)
							(mid 0.402042 0.402042)
							(end 0.4318 0.3302)
						)
						(arc
							(start 0.4318 -0.3302)
							(mid 0.402042 -0.402042)
							(end 0.3302 -0.4318)
						)
					)
					(width 0)
					(fill yes)
				)
			)
		)
		(pad "2" smd custom
			(at 0 0.762 180)
			(size 0.2159 0.2159)
			(layers "F.Cu" "F.Mask" "F.Paste")
			(net "GND")
			(options
				(clearance outline)
				(anchor circle)
			)
			(primitives
				(gr_poly
					(pts
						(arc
							(start -0.3302 -0.4318)
							(mid -0.402042 -0.402042)
							(end -0.4318 -0.3302)
						)
						(arc
							(start -0.4318 0.3302)
							(mid -0.402042 0.402042)
							(end -0.3302 0.4318)
						)
						(arc
							(start 0.3302 0.4318)
							(mid 0.402042 0.402042)
							(end 0.4318 0.3302)
						)
						(arc
							(start 0.4318 -0.3302)
							(mid 0.402042 -0.402042)
							(end 0.3302 -0.4318)
						)
					)
					(width 0)
					(fill yes)
				)
			)
		)
	)
)
